# T6G (Grand Teton) — schematic netlist excerpt (pin names and nets, part order shuffled) for the footprints in the layout excerpt that follows; sources: Cadence DE-HDL packaged netlist, KiCad conversion of 04192023_DAF0TMB3IC0_F0TG_MB_C_brd_V02_OCP.brd

C2274  Q_CAP  22UF 4V 20% X6S  pkg C0402  page 72 : A = PVDDIO_P1 ; B = GND
R124  Q_RES  1K 1% EMPTY  pkg 0402LF  page 207 : A = PVDD18_S5_P0 ; B = PVDD11_S3_P0_OCP_N_R

(kicad_pcb
	(version 20260206)
	(generator "pcbnew")
	(generator_version "10.0")
	(general
		(thickness 1.6)
		(legacy_teardrops no)
	)
	(paper "A4")
	(title_block
		(title "04192023_DAF0TMB3IC0_F0TG_MB_C_brd_V02_OCP.brd")
		(comment 1 "Grand Teton / footprints 3537-3538 of 8354")
	)
	(layers
		(0 "F.Cu" signal "TOP")
		(4 "In1.Cu" signal "GND")
		(6 "In2.Cu" signal "IN1")
		(8 "In3.Cu" signal "GND1")
		(10 "In4.Cu" signal "IN2")
		(12 "In5.Cu" signal "GND2")
		(14 "In6.Cu" signal "IN3")
		(16 "In7.Cu" signal "GND3")
		(18 "In8.Cu" signal "VCC")
		(20 "In9.Cu" signal "VCC1")
		(22 "In10.Cu" signal "GND4")
		(24 "In11.Cu" signal "IN4")
		(26 "In12.Cu" signal "GND5")
		(28 "In13.Cu" signal "IN5")
		(30 "In14.Cu" signal "GND6")
		(32 "In15.Cu" signal "IN6")
		(34 "In16.Cu" signal "GND7")
		(2 "B.Cu" signal "BOTTOM")
		(9 "F.Adhes" user "F.Adhesive")
		(11 "B.Adhes" user "B.Adhesive")
		(13 "F.Paste" user "Package Geometry/Pastemask Top")
		(15 "B.Paste" user "Package Geometry/Pastemask Bottom")
		(5 "F.SilkS" user "Ref Des/Silkscreen Top")
		(7 "B.SilkS" user "Ref Des/Silkscreen Bottom")
		(1 "F.Mask" user "Board Geometry/Soldermask Top")
		(3 "B.Mask" user "Board Geometry/Soldermask Bottom")
		(17 "Dwgs.User" user "User.Drawings")
		(19 "Cmts.User" user "User.Comments")
		(21 "Eco1.User" user "User.Eco1")
		(23 "Eco2.User" user "User.Eco2")
		(25 "Edge.Cuts" user "Board Geometry/Outline")
		(27 "Margin" user)
		(31 "F.CrtYd" user "Package Geometry/Place Bound Top")
		(29 "B.CrtYd" user "Package Geometry/Place Bound Bottom")
		(35 "F.Fab" user "Ref Des/Assembly Top")
		(33 "B.Fab" user "Ref Des/Assembly Bottom")
	)
	(footprint ""
		(layer "F.Cu")
		(at 105.960164 -260.305296)
		(property "Reference" "C2274"
			(at 0 0 0)
			(layer "F.SilkS")
			(hide yes)
			(effects
				(font
					(size 1.27 1.27)
				)
			)
		)
		(property "Value" ""
			(at 0 0 0)
			(layer "F.Fab")
			(effects
				(font
					(size 1.27 1.27)
				)
			)
		)
		(duplicate_pad_numbers_are_jumpers no)
		(fp_line
			(start -0.7874 -0.4064)
			(end 0.7874 -0.4064)
			(stroke
				(width 0.1524)
				(type default)
			)
			(layer "F.SilkS")
		)
		(fp_line
			(start -0.7874 0.4064)
			(end -0.7874 -0.4064)
			(stroke
				(width 0.1524)
				(type default)
			)
			(layer "F.SilkS")
		)
		(fp_line
			(start 0.7874 -0.4064)
			(end 0.7874 0.4064)
			(stroke
				(width 0.1524)
				(type default)
			)
			(layer "F.SilkS")
		)
		(fp_line
			(start 0.7874 0.4064)
			(end -0.7874 0.4064)
			(stroke
				(width 0.1524)
				(type default)
			)
			(layer "F.SilkS")
		)
		(fp_line
			(start -0.67945 -0.305054)
			(end -0.12065 -0.305054)
			(stroke
				(width 0.1)
				(type default)
			)
			(layer "F.Fab")
		)
		(fp_line
			(start -0.67945 0.3048)
			(end -0.67945 -0.305054)
			(stroke
				(width 0.1)
				(type default)
			)
			(layer "F.Fab")
		)
		(fp_line
			(start -0.12065 -0.305054)
			(end -0.12065 -0.2794)
			(stroke
				(width 0.1)
				(type default)
			)
			(layer "F.Fab")
		)
		(fp_line
			(start -0.12065 -0.2794)
			(end 0.12065 -0.2794)
			(stroke
				(width 0.1)
				(type default)
			)
			(layer "F.Fab")
		)
		(fp_line
			(start -0.12065 0.2794)
			(end -0.12065 0.3048)
			(stroke
				(width 0.1)
				(type default)
			)
			(layer "F.Fab")
		)
		(fp_line
			(start -0.12065 0.3048)
			(end -0.67945 0.3048)
			(stroke
				(width 0.1)
				(type default)
			)
			(layer "F.Fab")
		)
		(fp_line
			(start 0.120396 0.2794)
			(end -0.12065 0.2794)
			(stroke
				(width 0.1)
				(type default)
			)
			(layer "F.Fab")
		)
		(fp_line
			(start 0.120396 0.3048)
			(end 0.120396 0.2794)
			(stroke
				(width 0.1)
				(type default)
			)
			(layer "F.Fab")
		)
		(fp_line
			(start 0.12065 -0.3048)
			(end 0.67945 -0.3048)
			(stroke
				(width 0.1)
				(type default)
			)
			(layer "F.Fab")
		)
		(fp_line
			(start 0.12065 -0.2794)
			(end 0.12065 -0.3048)
			(stroke
				(width 0.1)
				(type default)
			)
			(layer "F.Fab")
		)
		(fp_line
			(start 0.67945 -0.3048)
			(end 0.67945 0.3048)
			(stroke
				(width 0.1)
				(type default)
			)
			(layer "F.Fab")
		)
		(fp_line
			(start 0.67945 0.3048)
			(end 0.120396 0.3048)
			(stroke
				(width 0.1)
				(type default)
			)
			(layer "F.Fab")
		)
		(pad "1" smd circle
			(at -0.40005 0)
			(size 0 0)
			(layers "F.Cu" "F.Mask" "F.Paste")
			(net "PVDDIO_P1")
		)
		(pad "2" smd circle
			(at 0.40005 0)
			(size 0 0)
			(layers "F.Cu" "F.Mask" "F.Paste")
			(net "GND")
		)
	)
	(footprint ""
		(layer "F.Cu")
		(at 423.62374 -359.836212 180)
		(property "Reference" "R124"
			(at 0 0 180)
			(layer "F.SilkS")
			(hide yes)
			(effects
				(font
					(size 1.27 1.27)
				)
			)
		)
		(property "Value" ""
			(at 0 0 180)
			(layer "F.Fab")
			(effects
				(font
					(size 1.27 1.27)
				)
			)
		)
		(duplicate_pad_numbers_are_jumpers no)
		(fp_line
			(start 0.7874 0.4064)
			(end -0.7874 0.4064)
			(stroke
				(width 0.1524)
				(type default)
			)
			(layer "F.SilkS")
		)
		(fp_line
			(start 0.7874 -0.4064)
			(end 0.7874 0.4064)
			(stroke
				(width 0.1524)
				(type default)
			)
			(layer "F.SilkS")
		)
		(fp_line
			(start -0.7874 0.4064)
			(end -0.7874 -0.4064)
			(stroke
				(width 0.1524)
				(type default)
			)
			(layer "F.SilkS")
		)
		(fp_line
			(start -0.7874 -0.4064)
			(end 0.7874 -0.4064)
			(stroke
				(width 0.1524)
				(type default)
			)
			(layer "F.SilkS")
		)
		(fp_line
			(start 0.67945 0.3048)
			(end 0.120396 0.3048)
			(stroke
				(width 0.1)
				(type default)
			)
			(layer "F.Fab")
		)
		(fp_line
			(start 0.67945 -0.3048)
			(end 0.67945 0.3048)
			(stroke
				(width 0.1)
				(type default)
			)
			(layer "F.Fab")
		)
		(fp_line
			(start 0.12065 -0.2794)
			(end 0.12065 -0.3048)
			(stroke
				(width 0.1)
				(type default)
			)
			(layer "F.Fab")
		)
		(fp_line
			(start 0.12065 -0.3048)
			(end 0.67945 -0.3048)
			(stroke
				(width 0.1)
				(type default)
			)
			(layer "F.Fab")
		)
		(fp_line
			(start 0.120396 0.3048)
			(end 0.120396 0.2794)
			(stroke
				(width 0.1)
				(type default)
			)
			(layer "F.Fab")
		)
		(fp_line
			(start 0.120396 0.2794)
			(end -0.12065 0.2794)
			(stroke
				(width 0.1)
				(type default)
			)
			(layer "F.Fab")
		)
		(fp_line
			(start -0.12065 0.3048)
			(end -0.67945 0.3048)
			(stroke
				(width 0.1)
				(type default)
			)
			(layer "F.Fab")
		)
		(fp_line
			(start -0.12065 0.2794)
			(end -0.12065 0.3048)
			(stroke
				(width 0.1)
				(type default)
			)
			(layer "F.Fab")
		)
		(fp_line
			(start -0.12065 -0.2794)
			(end 0.12065 -0.2794)
			(stroke
				(width 0.1)
				(type default)
			)
			(layer "F.Fab")
		)
		(fp_line
			(start -0.12065 -0.305054)
			(end -0.12065 -0.2794)
			(stroke
				(width 0.1)
				(type default)
			)
			(layer "F.Fab")
		)
		(fp_line
			(start -0.67945 0.3048)
			(end -0.67945 -0.305054)
			(stroke
				(width 0.1)
				(type default)
			)
			(layer "F.Fab")
		)
		(fp_line
			(start -0.67945 -0.305054)
			(end -0.12065 -0.305054)
			(stroke
				(width 0.1)
				(type default)
			)
			(layer "F.Fab")
		)
		(pad "1" smd circle
			(at -0.40005 0 180)
			(size 0 0)
			(layers "F.Cu" "F.Mask" "F.Paste")
			(net "PVDD18_S5_P0")
		)
		(pad "2" smd circle
			(at 0.40005 0 180)
			(size 0 0)
			(layers "F.Cu" "F.Mask" "F.Paste")
			(net "PVDD11_S3_P0_OCP_N_R")
		)
	)
)
